FILE_TYPE = CONNECTIVITY;
{Allegro Design Entry HDL 17.2-2016 S081 (4005846) 1/11/2022}
"PAGE_NUMBER" = 207;
0"NC";
END.
